(kicad_pcb
	(version 20260206)
	(generator "pcbnew")
	(generator_version "10.0")
	(general
		(thickness 1.6)
		(legacy_teardrops no)
	)
	(paper "A4")
	(title_block
		(title "04192023_DAF0TMB3IC0_F0TG_MB_C_brd_V02_OCP.brd")
		(comment 1 "Grand Teton / footprints 5051-5058 of 8354")
	)
	(layers
		(0 "F.Cu" signal "TOP")
		(4 "In1.Cu" signal "GND")
		(6 "In2.Cu" signal "IN1")
		(8 "In3.Cu" signal "GND1")
		(10 "In4.Cu" signal "IN2")
		(12 "In5.Cu" signal "GND2")
		(14 "In6.Cu" signal "IN3")
		(16 "In7.Cu" signal "GND3")
		(18 "In8.Cu" signal "VCC")
		(20 "In9.Cu" signal "VCC1")
		(22 "In10.Cu" signal "GND4")
		(24 "In11.Cu" signal "IN4")
		(26 "In12.Cu" signal "GND5")
		(28 "In13.Cu" signal "IN5")
		(30 "In14.Cu" signal "GND6")
		(32 "In15.Cu" signal "IN6")
		(34 "In16.Cu" signal "GND7")
		(2 "B.Cu" signal "BOTTOM")
		(9 "F.Adhes" user "F.Adhesive")
		(11 "B.Adhes" user "B.Adhesive")
		(13 "F.Paste" user "Package Geometry/Pastemask Top")
		(15 "B.Paste" user "Package Geometry/Pastemask Bottom")
		(5 "F.SilkS" user "Ref Des/Silkscreen Top")
		(7 "B.SilkS" user "Ref Des/Silkscreen Bottom")
		(1 "F.Mask" user "Board Geometry/Soldermask Top")
		(3 "B.Mask" user "Board Geometry/Soldermask Bottom")
		(17 "Dwgs.User" user "User.Drawings")
		(19 "Cmts.User" user "User.Comments")
		(21 "Eco1.User" user "User.Eco1")
		(23 "Eco2.User" user "User.Eco2")
		(25 "Edge.Cuts" user "Board Geometry/Outline")
		(27 "Margin" user)
		(31 "F.CrtYd" user "Package Geometry/Place Bound Top")
		(29 "B.CrtYd" user "Package Geometry/Place Bound Bottom")
		(35 "F.Fab" user "Ref Des/Assembly Top")
		(33 "B.Fab" user "Ref Des/Assembly Bottom")
	)
	(footprint ""
		(layer "B.Cu")
		(at 369.62588 -258.830064)
		(property "Reference" "C2537"
			(at 0 0 0)
			(layer "B.SilkS")
			(hide yes)
			(effects
				(font
					(size 1.27 1.27)
				)
				(justify mirror)
			)
		)
		(property "Value" ""
			(at 0 0 0)
			(layer "B.Fab")
			(effects
				(font
					(size 1.27 1.27)
				)
				(justify mirror)
			)
		)
		(duplicate_pad_numbers_are_jumpers no)
		(fp_line
			(start -0.7874 -0.4064)
			(end -0.7874 0.4064)
			(stroke
				(width 0.1524)
				(type default)
			)
			(layer "B.SilkS")
		)
		(fp_line
			(start -0.7874 0.4064)
			(end 0.7874 0.4064)
			(stroke
				(width 0.1524)
				(type default)
			)
			(layer "B.SilkS")
		)
		(fp_line
			(start 0.7874 -0.4064)
			(end -0.7874 -0.4064)
			(stroke
				(width 0.1524)
				(type default)
			)
			(layer "B.SilkS")
		)
		(fp_line
			(start 0.7874 0.4064)
			(end 0.7874 -0.4064)
			(stroke
				(width 0.1524)
				(type default)
			)
			(layer "B.SilkS")
		)
		(fp_line
			(start -0.67945 -0.3048)
			(end -0.67945 0.3048)
			(stroke
				(width 0.1)
				(type default)
			)
			(layer "B.Fab")
		)
		(fp_line
			(start -0.67945 0.3048)
			(end -0.120396 0.3048)
			(stroke
				(width 0.1)
				(type default)
			)
			(layer "B.Fab")
		)
		(fp_line
			(start -0.12065 -0.3048)
			(end -0.67945 -0.3048)
			(stroke
				(width 0.1)
				(type default)
			)
			(layer "B.Fab")
		)
		(fp_line
			(start -0.12065 -0.2794)
			(end -0.12065 -0.3048)
			(stroke
				(width 0.1)
				(type default)
			)
			(layer "B.Fab")
		)
		(fp_line
			(start -0.120396 0.2794)
			(end 0.12065 0.2794)
			(stroke
				(width 0.1)
				(type default)
			)
			(layer "B.Fab")
		)
		(fp_line
			(start -0.120396 0.3048)
			(end -0.120396 0.2794)
			(stroke
				(width 0.1)
				(type default)
			)
			(layer "B.Fab")
		)
		(fp_line
			(start 0.12065 -0.305054)
			(end 0.12065 -0.2794)
			(stroke
				(width 0.1)
				(type default)
			)
			(layer "B.Fab")
		)
		(fp_line
			(start 0.12065 -0.2794)
			(end -0.12065 -0.2794)
			(stroke
				(width 0.1)
				(type default)
			)
			(layer "B.Fab")
		)
		(fp_line
			(start 0.12065 0.2794)
			(end 0.12065 0.3048)
			(stroke
				(width 0.1)
				(type default)
			)
			(layer "B.Fab")
		)
		(fp_line
			(start 0.12065 0.3048)
			(end 0.67945 0.3048)
			(stroke
				(width 0.1)
				(type default)
			)
			(layer "B.Fab")
		)
		(fp_line
			(start 0.67945 -0.305054)
			(end 0.12065 -0.305054)
			(stroke
				(width 0.1)
				(type default)
			)
			(layer "B.Fab")
		)
		(fp_line
			(start 0.67945 0.3048)
			(end 0.67945 -0.305054)
			(stroke
				(width 0.1)
				(type default)
			)
			(layer "B.Fab")
		)
		(pad "1" smd circle
			(at 0.40005 0 180)
			(size 0 0)
			(layers "B.Cu" "B.Mask" "B.Paste")
			(net "PVDDCR_SOC_P0")
		)
		(pad "2" smd circle
			(at -0.40005 0 180)
			(size 0 0)
			(layers "B.Cu" "B.Mask" "B.Paste")
			(net "GND")
		)
	)
	(footprint ""
		(layer "B.Cu")
		(at 120.055386 -268.418564)
		(property "Reference" "C2398"
			(at 0 0 0)
			(layer "B.SilkS")
			(hide yes)
			(effects
				(font
					(size 1.27 1.27)
				)
				(justify mirror)
			)
		)
		(property "Value" ""
			(at 0 0 0)
			(layer "B.Fab")
			(effects
				(font
					(size 1.27 1.27)
				)
				(justify mirror)
			)
		)
		(duplicate_pad_numbers_are_jumpers no)
		(fp_line
			(start -0.7874 -0.4064)
			(end -0.7874 0.4064)
			(stroke
				(width 0.1524)
				(type default)
			)
			(layer "B.SilkS")
		)
		(fp_line
			(start -0.7874 0.4064)
			(end 0.7874 0.4064)
			(stroke
				(width 0.1524)
				(type default)
			)
			(layer "B.SilkS")
		)
		(fp_line
			(start 0.7874 -0.4064)
			(end -0.7874 -0.4064)
			(stroke
				(width 0.1524)
				(type default)
			)
			(layer "B.SilkS")
		)
		(fp_line
			(start 0.7874 0.4064)
			(end 0.7874 -0.4064)
			(stroke
				(width 0.1524)
				(type default)
			)
			(layer "B.SilkS")
		)
		(fp_line
			(start -0.67945 -0.3048)
			(end -0.67945 0.3048)
			(stroke
				(width 0.1)
				(type default)
			)
			(layer "B.Fab")
		)
		(fp_line
			(start -0.67945 0.3048)
			(end -0.120396 0.3048)
			(stroke
				(width 0.1)
				(type default)
			)
			(layer "B.Fab")
		)
		(fp_line
			(start -0.12065 -0.3048)
			(end -0.67945 -0.3048)
			(stroke
				(width 0.1)
				(type default)
			)
			(layer "B.Fab")
		)
		(fp_line
			(start -0.12065 -0.2794)
			(end -0.12065 -0.3048)
			(stroke
				(width 0.1)
				(type default)
			)
			(layer "B.Fab")
		)
		(fp_line
			(start -0.120396 0.2794)
			(end 0.12065 0.2794)
			(stroke
				(width 0.1)
				(type default)
			)
			(layer "B.Fab")
		)
		(fp_line
			(start -0.120396 0.3048)
			(end -0.120396 0.2794)
			(stroke
				(width 0.1)
				(type default)
			)
			(layer "B.Fab")
		)
		(fp_line
			(start 0.12065 -0.305054)
			(end 0.12065 -0.2794)
			(stroke
				(width 0.1)
				(type default)
			)
			(layer "B.Fab")
		)
		(fp_line
			(start 0.12065 -0.2794)
			(end -0.12065 -0.2794)
			(stroke
				(width 0.1)
				(type default)
			)
			(layer "B.Fab")
		)
		(fp_line
			(start 0.12065 0.2794)
			(end 0.12065 0.3048)
			(stroke
				(width 0.1)
				(type default)
			)
			(layer "B.Fab")
		)
		(fp_line
			(start 0.12065 0.3048)
			(end 0.67945 0.3048)
			(stroke
				(width 0.1)
				(type default)
			)
			(layer "B.Fab")
		)
		(fp_line
			(start 0.67945 -0.305054)
			(end 0.12065 -0.305054)
			(stroke
				(width 0.1)
				(type default)
			)
			(layer "B.Fab")
		)
		(fp_line
			(start 0.67945 0.3048)
			(end 0.67945 -0.305054)
			(stroke
				(width 0.1)
				(type default)
			)
			(layer "B.Fab")
		)
		(pad "1" smd circle
			(at 0.40005 0 180)
			(size 0 0)
			(layers "B.Cu" "B.Mask" "B.Paste")
			(net "PVDDCR_CPU1_P1")
		)
		(pad "2" smd circle
			(at -0.40005 0 180)
			(size 0 0)
			(layers "B.Cu" "B.Mask" "B.Paste")
			(net "GND")
		)
	)
	(footprint ""
		(layer "B.Cu")
		(at 64.401954 -165.119812 90)
		(property "Reference" "PC129_6"
			(at 0 0 90)
			(layer "B.SilkS")
			(hide yes)
			(effects
				(font
					(size 1.27 1.27)
				)
				(justify mirror)
			)
		)
		(property "Value" ""
			(at 0 0 90)
			(layer "B.Fab")
			(effects
				(font
					(size 1.27 1.27)
				)
				(justify mirror)
			)
		)
		(duplicate_pad_numbers_are_jumpers no)
		(fp_line
			(start 1.524 -0.762)
			(end -1.524 -0.762)
			(stroke
				(width 0.1524)
				(type default)
			)
			(layer "B.SilkS")
		)
		(fp_line
			(start -1.524 -0.762)
			(end -1.524 0.762)
			(stroke
				(width 0.1524)
				(type default)
			)
			(layer "B.SilkS")
		)
		(fp_line
			(start 1.524 0.762)
			(end 1.524 -0.762)
			(stroke
				(width 0.1524)
				(type default)
			)
			(layer "B.SilkS")
		)
		(fp_line
			(start -1.524 0.762)
			(end 1.524 0.762)
			(stroke
				(width 0.1524)
				(type default)
			)
			(layer "B.SilkS")
		)
		(fp_line
			(start 1.1049 -0.724916)
			(end 1.1049 0.724916)
			(stroke
				(width 0.1)
				(type default)
			)
			(layer "B.Fab")
		)
		(fp_line
			(start -1.1049 -0.724916)
			(end 1.1049 -0.724916)
			(stroke
				(width 0.1)
				(type default)
			)
			(layer "B.Fab")
		)
		(fp_line
			(start 1.1049 0.724916)
			(end -1.1049 0.724916)
			(stroke
				(width 0.1)
				(type default)
			)
			(layer "B.Fab")
		)
		(fp_line
			(start -1.1049 0.724916)
			(end -1.1049 -0.724916)
			(stroke
				(width 0.1)
				(type default)
			)
			(layer "B.Fab")
		)
		(pad "1" smd rect
			(at 0.889 0 90)
			(size 1.016 1.27)
			(layers "B.Cu" "B.Mask" "B.Paste")
			(net "SW_P12V_AUX_PVDDCR_CPU0_P1_FLT")
		)
		(pad "2" smd rect
			(at -0.889 0 90)
			(size 1.016 1.27)
			(layers "B.Cu" "B.Mask" "B.Paste")
			(net "GND")
		)
	)
	(footprint ""
		(layer "B.Cu")
		(at 242.702842 -382.467358 180)
		(property "Reference" "PC1750"
			(at 0 0 0)
			(layer "B.SilkS")
			(hide yes)
			(effects
				(font
					(size 1.27 1.27)
				)
				(justify mirror)
			)
		)
		(property "Value" ""
			(at 0 0 0)
			(layer "B.Fab")
			(effects
				(font
					(size 1.27 1.27)
				)
				(justify mirror)
			)
		)
		(duplicate_pad_numbers_are_jumpers no)
		(fp_line
			(start 0.7874 0.4064)
			(end 0.7874 -0.4064)
			(stroke
				(width 0.1524)
				(type default)
			)
			(layer "B.SilkS")
		)
		(fp_line
			(start 0.7874 -0.4064)
			(end -0.7874 -0.4064)
			(stroke
				(width 0.1524)
				(type default)
			)
			(layer "B.SilkS")
		)
		(fp_line
			(start -0.7874 0.4064)
			(end 0.7874 0.4064)
			(stroke
				(width 0.1524)
				(type default)
			)
			(layer "B.SilkS")
		)
		(fp_line
			(start -0.7874 -0.4064)
			(end -0.7874 0.4064)
			(stroke
				(width 0.1524)
				(type default)
			)
			(layer "B.SilkS")
		)
		(fp_line
			(start 0.67945 0.3048)
			(end 0.67945 -0.305054)
			(stroke
				(width 0.1)
				(type default)
			)
			(layer "B.Fab")
		)
		(fp_line
			(start 0.67945 -0.305054)
			(end 0.12065 -0.305054)
			(stroke
				(width 0.1)
				(type default)
			)
			(layer "B.Fab")
		)
		(fp_line
			(start 0.12065 0.3048)
			(end 0.67945 0.3048)
			(stroke
				(width 0.1)
				(type default)
			)
			(layer "B.Fab")
		)
		(fp_line
			(start 0.12065 0.2794)
			(end 0.12065 0.3048)
			(stroke
				(width 0.1)
				(type default)
			)
			(layer "B.Fab")
		)
		(fp_line
			(start 0.12065 -0.2794)
			(end -0.12065 -0.2794)
			(stroke
				(width 0.1)
				(type default)
			)
			(layer "B.Fab")
		)
		(fp_line
			(start 0.12065 -0.305054)
			(end 0.12065 -0.2794)
			(stroke
				(width 0.1)
				(type default)
			)
			(layer "B.Fab")
		)
		(fp_line
			(start -0.120396 0.3048)
			(end -0.120396 0.2794)
			(stroke
				(width 0.1)
				(type default)
			)
			(layer "B.Fab")
		)
		(fp_line
			(start -0.120396 0.2794)
			(end 0.12065 0.2794)
			(stroke
				(width 0.1)
				(type default)
			)
			(layer "B.Fab")
		)
		(fp_line
			(start -0.12065 -0.2794)
			(end -0.12065 -0.3048)
			(stroke
				(width 0.1)
				(type default)
			)
			(layer "B.Fab")
		)
		(fp_line
			(start -0.12065 -0.3048)
			(end -0.67945 -0.3048)
			(stroke
				(width 0.1)
				(type default)
			)
			(layer "B.Fab")
		)
		(fp_line
			(start -0.67945 0.3048)
			(end -0.120396 0.3048)
			(stroke
				(width 0.1)
				(type default)
			)
			(layer "B.Fab")
		)
		(fp_line
			(start -0.67945 -0.3048)
			(end -0.67945 0.3048)
			(stroke
				(width 0.1)
				(type default)
			)
			(layer "B.Fab")
		)
		(pad "1" smd circle
			(at 0.40005 0)
			(size 0 0)
			(layers "B.Cu" "B.Mask" "B.Paste")
			(net "P12V_AUX")
		)
		(pad "2" smd circle
			(at -0.40005 0)
			(size 0 0)
			(layers "B.Cu" "B.Mask" "B.Paste")
			(net "P12V_HSC_GATE2")
		)
	)
	(footprint ""
		(layer "B.Cu")
		(at 89.646252 -388.011162 -90)
		(property "Reference" "C287"
			(at 0 0 90)
			(layer "B.SilkS")
			(hide yes)
			(effects
				(font
					(size 1.27 1.27)
				)
				(justify mirror)
			)
		)
		(property "Value" ""
			(at 0 0 90)
			(layer "B.Fab")
			(effects
				(font
					(size 1.27 1.27)
				)
				(justify mirror)
			)
		)
		(duplicate_pad_numbers_are_jumpers no)
		(fp_line
			(start -0.299974 0.150114)
			(end 0.299974 0.150114)
			(stroke
				(width 0.1)
				(type default)
			)
			(layer "B.Fab")
		)
		(fp_line
			(start 0.299974 0.150114)
			(end 0.299974 -0.150114)
			(stroke
				(width 0.1)
				(type default)
			)
			(layer "B.Fab")
		)
		(fp_line
			(start -0.299974 -0.150114)
			(end -0.299974 0.150114)
			(stroke
				(width 0.1)
				(type default)
			)
			(layer "B.Fab")
		)
		(fp_line
			(start 0.299974 -0.150114)
			(end -0.299974 -0.150114)
			(stroke
				(width 0.1)
				(type default)
			)
			(layer "B.Fab")
		)
		(pad "1" smd rect
			(at 0.2667 0 90)
			(size 0.3048 0.381)
			(layers "B.Cu" "B.Mask" "B.Paste")
			(net "P1V8_CPU1_RT1_1A")
		)
		(pad "2" smd rect
			(at -0.2667 0 90)
			(size 0.3048 0.381)
			(layers "B.Cu" "B.Mask" "B.Paste")
			(net "GND")
		)
	)
	(footprint ""
		(layer "B.Cu")
		(at 357.835454 -251.78131)
		(property "Reference" "C2593"
			(at 0 0 0)
			(layer "B.SilkS")
			(hide yes)
			(effects
				(font
					(size 1.27 1.27)
				)
				(justify mirror)
			)
		)
		(property "Value" ""
			(at 0 0 0)
			(layer "B.Fab")
			(effects
				(font
					(size 1.27 1.27)
				)
				(justify mirror)
			)
		)
		(duplicate_pad_numbers_are_jumpers no)
		(fp_line
			(start -0.7874 -0.4064)
			(end -0.7874 0.4064)
			(stroke
				(width 0.1524)
				(type default)
			)
			(layer "B.SilkS")
		)
		(fp_line
			(start -0.7874 0.4064)
			(end 0.7874 0.4064)
			(stroke
				(width 0.1524)
				(type default)
			)
			(layer "B.SilkS")
		)
		(fp_line
			(start 0.7874 -0.4064)
			(end -0.7874 -0.4064)
			(stroke
				(width 0.1524)
				(type default)
			)
			(layer "B.SilkS")
		)
		(fp_line
			(start 0.7874 0.4064)
			(end 0.7874 -0.4064)
			(stroke
				(width 0.1524)
				(type default)
			)
			(layer "B.SilkS")
		)
		(fp_line
			(start -0.67945 -0.3048)
			(end -0.67945 0.3048)
			(stroke
				(width 0.1)
				(type default)
			)
			(layer "B.Fab")
		)
		(fp_line
			(start -0.67945 0.3048)
			(end -0.120396 0.3048)
			(stroke
				(width 0.1)
				(type default)
			)
			(layer "B.Fab")
		)
		(fp_line
			(start -0.12065 -0.3048)
			(end -0.67945 -0.3048)
			(stroke
				(width 0.1)
				(type default)
			)
			(layer "B.Fab")
		)
		(fp_line
			(start -0.12065 -0.2794)
			(end -0.12065 -0.3048)
			(stroke
				(width 0.1)
				(type default)
			)
			(layer "B.Fab")
		)
		(fp_line
			(start -0.120396 0.2794)
			(end 0.12065 0.2794)
			(stroke
				(width 0.1)
				(type default)
			)
			(layer "B.Fab")
		)
		(fp_line
			(start -0.120396 0.3048)
			(end -0.120396 0.2794)
			(stroke
				(width 0.1)
				(type default)
			)
			(layer "B.Fab")
		)
		(fp_line
			(start 0.12065 -0.305054)
			(end 0.12065 -0.2794)
			(stroke
				(width 0.1)
				(type default)
			)
			(layer "B.Fab")
		)
		(fp_line
			(start 0.12065 -0.2794)
			(end -0.12065 -0.2794)
			(stroke
				(width 0.1)
				(type default)
			)
			(layer "B.Fab")
		)
		(fp_line
			(start 0.12065 0.2794)
			(end 0.12065 0.3048)
			(stroke
				(width 0.1)
				(type default)
			)
			(layer "B.Fab")
		)
		(fp_line
			(start 0.12065 0.3048)
			(end 0.67945 0.3048)
			(stroke
				(width 0.1)
				(type default)
			)
			(layer "B.Fab")
		)
		(fp_line
			(start 0.67945 -0.305054)
			(end 0.12065 -0.305054)
			(stroke
				(width 0.1)
				(type default)
			)
			(layer "B.Fab")
		)
		(fp_line
			(start 0.67945 0.3048)
			(end 0.67945 -0.305054)
			(stroke
				(width 0.1)
				(type default)
			)
			(layer "B.Fab")
		)
		(pad "1" smd circle
			(at 0.40005 0 180)
			(size 0 0)
			(layers "B.Cu" "B.Mask" "B.Paste")
			(net "PVDDCR_SOC_P0")
		)
		(pad "2" smd circle
			(at -0.40005 0 180)
			(size 0 0)
			(layers "B.Cu" "B.Mask" "B.Paste")
			(net "GND")
		)
	)
	(footprint ""
		(layer "B.Cu")
		(at 112.518444 -387.05028)
		(property "Reference" "C488"
			(at 0 0 0)
			(layer "B.SilkS")
			(hide yes)
			(effects
				(font
					(size 1.27 1.27)
				)
				(justify mirror)
			)
		)
		(property "Value" ""
			(at 0 0 0)
			(layer "B.Fab")
			(effects
				(font
					(size 1.27 1.27)
				)
				(justify mirror)
			)
		)
		(duplicate_pad_numbers_are_jumpers no)
		(fp_line
			(start -0.299974 -0.150114)
			(end -0.299974 0.150114)
			(stroke
				(width 0.1)
				(type default)
			)
			(layer "B.Fab")
		)
		(fp_line
			(start -0.299974 0.150114)
			(end 0.299974 0.150114)
			(stroke
				(width 0.1)
				(type default)
			)
			(layer "B.Fab")
		)
		(fp_line
			(start 0.299974 -0.150114)
			(end -0.299974 -0.150114)
			(stroke
				(width 0.1)
				(type default)
			)
			(layer "B.Fab")
		)
		(fp_line
			(start 0.299974 0.150114)
			(end 0.299974 -0.150114)
			(stroke
				(width 0.1)
				(type default)
			)
			(layer "B.Fab")
		)
		(pad "1" smd rect
			(at 0.2667 0 180)
			(size 0.3048 0.381)
			(layers "B.Cu" "B.Mask" "B.Paste")
			(net "P0V9_CPU1_RT3_2A")
		)
		(pad "2" smd rect
			(at -0.2667 0 180)
			(size 0.3048 0.381)
			(layers "B.Cu" "B.Mask" "B.Paste")
			(net "GND")
		)
	)
	(footprint ""
		(layer "B.Cu")
		(at 109.550454 -31.549086 180)
		(property "Reference" "C6093"
			(at 0 0 0)
			(layer "B.SilkS")
			(hide yes)
			(effects
				(font
					(size 1.27 1.27)
				)
				(justify mirror)
			)
		)
		(property "Value" ""
			(at 0 0 0)
			(layer "B.Fab")
			(effects
				(font
					(size 1.27 1.27)
				)
				(justify mirror)
			)
		)
		(duplicate_pad_numbers_are_jumpers no)
		(fp_line
			(start 0.7874 0.4064)
			(end 0.7874 -0.4064)
			(stroke
				(width 0.1524)
				(type default)
			)
			(layer "B.SilkS")
		)
		(fp_line
			(start 0.7874 -0.4064)
			(end -0.7874 -0.4064)
			(stroke
				(width 0.1524)
				(type default)
			)
			(layer "B.SilkS")
		)
		(fp_line
			(start -0.7874 0.4064)
			(end 0.7874 0.4064)
			(stroke
				(width 0.1524)
				(type default)
			)
			(layer "B.SilkS")
		)
		(fp_line
			(start -0.7874 -0.4064)
			(end -0.7874 0.4064)
			(stroke
				(width 0.1524)
				(type default)
			)
			(layer "B.SilkS")
		)
		(fp_line
			(start 0.67945 0.3048)
			(end 0.67945 -0.305054)
			(stroke
				(width 0.1)
				(type default)
			)
			(layer "B.Fab")
		)
		(fp_line
			(start 0.67945 -0.305054)
			(end 0.12065 -0.305054)
			(stroke
				(width 0.1)
				(type default)
			)
			(layer "B.Fab")
		)
		(fp_line
			(start 0.12065 0.3048)
			(end 0.67945 0.3048)
			(stroke
				(width 0.1)
				(type default)
			)
			(layer "B.Fab")
		)
		(fp_line
			(start 0.12065 0.2794)
			(end 0.12065 0.3048)
			(stroke
				(width 0.1)
				(type default)
			)
			(layer "B.Fab")
		)
		(fp_line
			(start 0.12065 -0.2794)
			(end -0.12065 -0.2794)
			(stroke
				(width 0.1)
				(type default)
			)
			(layer "B.Fab")
		)
		(fp_line
			(start 0.12065 -0.305054)
			(end 0.12065 -0.2794)
			(stroke
				(width 0.1)
				(type default)
			)
			(layer "B.Fab")
		)
		(fp_line
			(start -0.120396 0.3048)
			(end -0.120396 0.2794)
			(stroke
				(width 0.1)
				(type default)
			)
			(layer "B.Fab")
		)
		(fp_line
			(start -0.120396 0.2794)
			(end 0.12065 0.2794)
			(stroke
				(width 0.1)
				(type default)
			)
			(layer "B.Fab")
		)
		(fp_line
			(start -0.12065 -0.2794)
			(end -0.12065 -0.3048)
			(stroke
				(width 0.1)
				(type default)
			)
			(layer "B.Fab")
		)
		(fp_line
			(start -0.12065 -0.3048)
			(end -0.67945 -0.3048)
			(stroke
				(width 0.1)
				(type default)
			)
			(layer "B.Fab")
		)
		(fp_line
			(start -0.67945 0.3048)
			(end -0.120396 0.3048)
			(stroke
				(width 0.1)
				(type default)
			)
			(layer "B.Fab")
		)
		(fp_line
			(start -0.67945 -0.3048)
			(end -0.67945 0.3048)
			(stroke
				(width 0.1)
				(type default)
			)
			(layer "B.Fab")
		)
		(pad "1" smd circle
			(at 0.40005 0)
			(size 0 0)
			(layers "B.Cu" "B.Mask" "B.Paste")
			(net "P3V3_AUX_CPU0_USB2_AVDD33")
		)
		(pad "2" smd circle
			(at -0.40005 0)
			(size 0 0)
			(layers "B.Cu" "B.Mask" "B.Paste")
			(net "GND")
		)
	)
)
